(kicad_pcb
	(version 20260206)
	(generator "pcbnew")
	(generator_version "10.0")
	(general
		(thickness 1.6)
		(legacy_teardrops no)
	)
	(paper "A4")
	(title_block
		(title "Bryce Canyon_IOM_M2_16342-2_OCP.brd")
		(comment 1 "Bryce Canyon / footprints 630-636 of 1146")
	)
	(layers
		(0 "F.Cu" signal "TOP")
		(4 "In1.Cu" signal "L2GND")
		(6 "In2.Cu" signal "L3")
		(8 "In3.Cu" signal "L4VCC")
		(10 "In4.Cu" signal "L5VCC")
		(12 "In5.Cu" signal "L6")
		(14 "In6.Cu" signal "L7GND")
		(2 "B.Cu" signal "BOTTOM")
		(9 "F.Adhes" user "F.Adhesive")
		(11 "B.Adhes" user "B.Adhesive")
		(13 "F.Paste" user "Package Geometry/Pastemask Top")
		(15 "B.Paste" user "Package Geometry/Pastemask Bottom")
		(5 "F.SilkS" user "Ref Des/Silkscreen Top")
		(7 "B.SilkS" user "Ref Des/Silkscreen Bottom")
		(1 "F.Mask" user "Board Geometry/Soldermask Top")
		(3 "B.Mask" user "Board Geometry/Soldermask Bottom")
		(17 "Dwgs.User" user "User.Drawings")
		(19 "Cmts.User" user "User.Comments")
		(21 "Eco1.User" user "User.Eco1")
		(23 "Eco2.User" user "User.Eco2")
		(25 "Edge.Cuts" user "Board Geometry/Outline")
		(27 "Margin" user)
		(31 "F.CrtYd" user "Package Geometry/Place Bound Top")
		(29 "B.CrtYd" user "Package Geometry/Place Bound Bottom")
		(35 "F.Fab" user "Ref Des/Assembly Top")
		(33 "B.Fab" user "Ref Des/Assembly Bottom")
	)
	(footprint ""
		(layer "F.Cu")
		(at 72.82053 -146.421602 -90)
		(property "Reference" "C513"
			(at 0 0 270)
			(layer "F.SilkS")
			(hide yes)
			(effects
				(font
					(size 1.27 1.27)
				)
			)
		)
		(property "Value" "SCD1U16V2KX-3GP"
			(at 1.1811 -2.7051 270)
			(unlocked yes)
			(layer "F.Fab")
			(hide yes)
			(effects
				(font
					(size 1.016 1.016)
					(thickness 0.1524)
				)
			)
		)
		(property "Device Type" "C402H22"
			(at 1.1811 -4.2291 270)
			(unlocked yes)
			(layer "F.Fab")
			(hide yes)
			(effects
				(font
					(size 1.016 1.016)
					(thickness 0.1524)
				)
			)
		)
		(duplicate_pad_numbers_are_jumpers no)
		(fp_rect
			(start -0.4318 0.9525)
			(end 0.4318 -0.9525)
			(stroke
				(width 0)
				(type default)
			)
			(fill no)
			(layer "F.CrtYd")
		)
		(fp_rect
			(start -0.4318 0.9525)
			(end 0.4318 -0.9525)
			(stroke
				(width 0)
				(type default)
			)
			(fill no)
			(layer "F.Fab")
		)
		(pad "1" smd custom
			(at 0 -0.4445 270)
			(size 0.1524 0.1524)
			(layers "F.Cu" "F.Mask" "F.Paste")
			(net "P3V3_STBY")
			(options
				(clearance outline)
				(anchor circle)
			)
			(primitives
				(gr_poly
					(pts
						(arc
							(start 0.3048 -0.2032)
							(mid 0.275042 -0.275042)
							(end 0.2032 -0.3048)
						)
						(arc
							(start -0.2032 -0.3048)
							(mid -0.275042 -0.275042)
							(end -0.3048 -0.2032)
						)
						(arc
							(start -0.3048 0.2032)
							(mid -0.275042 0.275042)
							(end -0.2032 0.3048)
						)
						(arc
							(start 0.2032 0.3048)
							(mid 0.275042 0.275042)
							(end 0.3048 0.2032)
						)
					)
					(width 0)
					(fill yes)
				)
			)
		)
		(pad "2" smd custom
			(at 0 0.4445 270)
			(size 0.1524 0.1524)
			(layers "F.Cu" "F.Mask" "F.Paste")
			(net "GND")
			(options
				(clearance outline)
				(anchor circle)
			)
			(primitives
				(gr_poly
					(pts
						(arc
							(start 0.3048 -0.2032)
							(mid 0.275042 -0.275042)
							(end 0.2032 -0.3048)
						)
						(arc
							(start -0.2032 -0.3048)
							(mid -0.275042 -0.275042)
							(end -0.3048 -0.2032)
						)
						(arc
							(start -0.3048 0.2032)
							(mid -0.275042 0.275042)
							(end -0.2032 0.3048)
						)
						(arc
							(start 0.2032 0.3048)
							(mid 0.275042 0.275042)
							(end 0.3048 0.2032)
						)
					)
					(width 0)
					(fill yes)
				)
			)
		)
	)
	(footprint ""
		(layer "F.Cu")
		(at 181.064154 -121.051828)
		(property "Reference" "R805"
			(at 0 0 0)
			(layer "F.SilkS")
			(hide yes)
			(effects
				(font
					(size 1.27 1.27)
				)
			)
		)
		(property "Value" "4K7R2F-GP"
			(at 0.064008 -3.993896 0)
			(unlocked yes)
			(layer "F.Fab")
			(hide yes)
			(effects
				(font
					(size 1.016 1.016)
					(thickness 0.1524)
				)
			)
		)
		(property "Device Type" "R402H16"
			(at 0.064008 -5.517896 0)
			(unlocked yes)
			(layer "F.Fab")
			(hide yes)
			(effects
				(font
					(size 1.016 1.016)
					(thickness 0.1524)
				)
			)
		)
		(duplicate_pad_numbers_are_jumpers no)
		(fp_line
			(start -0.508 -0.9398)
			(end -0.508 0.9398)
			(stroke
				(width 0.1524)
				(type default)
			)
			(layer "F.SilkS")
		)
		(fp_line
			(start 0.508 -0.9398)
			(end -0.508 -0.9398)
			(stroke
				(width 0.1524)
				(type default)
			)
			(layer "F.SilkS")
		)
		(fp_rect
			(start -0.508 0.9398)
			(end 0.508 -0.9398)
			(stroke
				(width 0)
				(type default)
			)
			(fill no)
			(layer "F.CrtYd")
		)
		(fp_rect
			(start -0.508 0.9398)
			(end 0.508 -0.9398)
			(stroke
				(width 0)
				(type default)
			)
			(fill no)
			(layer "F.Fab")
		)
		(pad "1" smd custom
			(at 0 -0.4445)
			(size 0.1397 0.1397)
			(layers "F.Cu" "F.Mask" "F.Paste")
			(net "M2_2_ALERT#")
			(options
				(clearance outline)
				(anchor circle)
			)
			(primitives
				(gr_poly
					(pts
						(arc
							(start -0.1778 -0.2794)
							(mid -0.249642 -0.249642)
							(end -0.2794 -0.1778)
						)
						(arc
							(start -0.2794 0.1778)
							(mid -0.249642 0.249642)
							(end -0.1778 0.2794)
						)
						(arc
							(start 0.1778 0.2794)
							(mid 0.249642 0.249642)
							(end 0.2794 0.1778)
						)
						(arc
							(start 0.2794 -0.1778)
							(mid 0.249642 -0.249642)
							(end 0.1778 -0.2794)
						)
					)
					(width 0)
					(fill yes)
				)
			)
		)
		(pad "2" smd custom
			(at 0 0.4445)
			(size 0.1397 0.1397)
			(layers "F.Cu" "F.Mask" "F.Paste")
			(net "P1V8_STBY")
			(options
				(clearance outline)
				(anchor circle)
			)
			(primitives
				(gr_poly
					(pts
						(arc
							(start -0.1778 -0.2794)
							(mid -0.249642 -0.249642)
							(end -0.2794 -0.1778)
						)
						(arc
							(start -0.2794 0.1778)
							(mid -0.249642 0.249642)
							(end -0.1778 0.2794)
						)
						(arc
							(start 0.1778 0.2794)
							(mid 0.249642 0.249642)
							(end 0.2794 0.1778)
						)
						(arc
							(start 0.2794 -0.1778)
							(mid 0.249642 -0.249642)
							(end 0.1778 -0.2794)
						)
					)
					(width 0)
					(fill yes)
				)
			)
		)
	)
	(footprint ""
		(layer "F.Cu")
		(at 214.152988 -40.719756 -90)
		(property "Reference" "C156"
			(at 0 0 270)
			(layer "F.SilkS")
			(hide yes)
			(effects
				(font
					(size 1.27 1.27)
				)
			)
		)
		(property "Value" "SC1U16V3KX-5GP"
			(at 0 -2.8194 270)
			(unlocked yes)
			(layer "F.Fab")
			(hide yes)
			(effects
				(font
					(size 1.016 1.016)
					(thickness 0.1524)
				)
			)
		)
		(property "Device Type" "C603H36"
			(at 0 -4.3434 270)
			(unlocked yes)
			(layer "F.Fab")
			(hide yes)
			(effects
				(font
					(size 1.016 1.016)
					(thickness 0.1524)
				)
			)
		)
		(duplicate_pad_numbers_are_jumpers no)
		(fp_line
			(start 0.508 0)
			(end -0.508 0)
			(stroke
				(width 0.2032)
				(type default)
			)
			(layer "F.SilkS")
		)
		(fp_rect
			(start -0.5842 1.3335)
			(end 0.5842 -1.3335)
			(stroke
				(width 0)
				(type default)
			)
			(fill no)
			(layer "F.CrtYd")
		)
		(fp_rect
			(start -0.5842 1.3335)
			(end 0.5842 -1.3335)
			(stroke
				(width 0)
				(type default)
			)
			(fill no)
			(layer "F.Fab")
		)
		(pad "1" smd custom
			(at 0 -0.762 270)
			(size 0.2159 0.2159)
			(layers "F.Cu" "F.Mask" "F.Paste")
			(net "P5V_EN_R")
			(options
				(clearance outline)
				(anchor circle)
			)
			(primitives
				(gr_poly
					(pts
						(arc
							(start -0.3302 -0.4318)
							(mid -0.402042 -0.402042)
							(end -0.4318 -0.3302)
						)
						(arc
							(start -0.4318 0.3302)
							(mid -0.402042 0.402042)
							(end -0.3302 0.4318)
						)
						(arc
							(start 0.3302 0.4318)
							(mid 0.402042 0.402042)
							(end 0.4318 0.3302)
						)
						(arc
							(start 0.4318 -0.3302)
							(mid 0.402042 -0.402042)
							(end 0.3302 -0.4318)
						)
					)
					(width 0)
					(fill yes)
				)
			)
		)
		(pad "2" smd custom
			(at 0 0.762 270)
			(size 0.2159 0.2159)
			(layers "F.Cu" "F.Mask" "F.Paste")
			(net "GND")
			(options
				(clearance outline)
				(anchor circle)
			)
			(primitives
				(gr_poly
					(pts
						(arc
							(start -0.3302 -0.4318)
							(mid -0.402042 -0.402042)
							(end -0.4318 -0.3302)
						)
						(arc
							(start -0.4318 0.3302)
							(mid -0.402042 0.402042)
							(end -0.3302 0.4318)
						)
						(arc
							(start 0.3302 0.4318)
							(mid 0.402042 0.402042)
							(end 0.4318 0.3302)
						)
						(arc
							(start 0.4318 -0.3302)
							(mid 0.402042 -0.402042)
							(end 0.3302 -0.4318)
						)
					)
					(width 0)
					(fill yes)
				)
			)
		)
	)
	(footprint ""
		(layer "F.Cu")
		(at 112.84839 -5.577078 -90)
		(property "Reference" "R456"
			(at 0 0 270)
			(layer "F.SilkS")
			(hide yes)
			(effects
				(font
					(size 1.27 1.27)
				)
			)
		)
		(property "Value" "0R2J-2-GP"
			(at 0.064008 -3.993896 270)
			(unlocked yes)
			(layer "F.Fab")
			(hide yes)
			(effects
				(font
					(size 1.016 1.016)
					(thickness 0.1524)
				)
			)
		)
		(property "Device Type" "R402H16"
			(at 0.064008 -5.517896 270)
			(unlocked yes)
			(layer "F.Fab")
			(hide yes)
			(effects
				(font
					(size 1.016 1.016)
					(thickness 0.1524)
				)
			)
		)
		(duplicate_pad_numbers_are_jumpers no)
		(fp_line
			(start -0.508 -0.9398)
			(end -0.508 0.9398)
			(stroke
				(width 0.1524)
				(type default)
			)
			(layer "F.SilkS")
		)
		(fp_line
			(start 0.508 -0.9398)
			(end -0.508 -0.9398)
			(stroke
				(width 0.1524)
				(type default)
			)
			(layer "F.SilkS")
		)
		(fp_rect
			(start -0.508 0.9398)
			(end 0.508 -0.9398)
			(stroke
				(width 0)
				(type default)
			)
			(fill no)
			(layer "F.CrtYd")
		)
		(fp_rect
			(start -0.508 0.9398)
			(end 0.508 -0.9398)
			(stroke
				(width 0)
				(type default)
			)
			(fill no)
			(layer "F.Fab")
		)
		(pad "1" smd custom
			(at 0 -0.4445 270)
			(size 0.1397 0.1397)
			(layers "F.Cu" "F.Mask" "F.Paste")
			(net "MB0_SPISS_PD")
			(options
				(clearance outline)
				(anchor circle)
			)
			(primitives
				(gr_poly
					(pts
						(arc
							(start -0.1778 -0.2794)
							(mid -0.249642 -0.249642)
							(end -0.2794 -0.1778)
						)
						(arc
							(start -0.2794 0.1778)
							(mid -0.249642 0.249642)
							(end -0.1778 0.2794)
						)
						(arc
							(start 0.1778 0.2794)
							(mid 0.249642 0.249642)
							(end 0.2794 0.1778)
						)
						(arc
							(start 0.2794 -0.1778)
							(mid 0.249642 -0.249642)
							(end 0.1778 -0.2794)
						)
					)
					(width 0)
					(fill yes)
				)
			)
		)
		(pad "2" smd custom
			(at 0 0.4445 270)
			(size 0.1397 0.1397)
			(layers "F.Cu" "F.Mask" "F.Paste")
			(net "AGND_CURRENT_MON")
			(options
				(clearance outline)
				(anchor circle)
			)
			(primitives
				(gr_poly
					(pts
						(arc
							(start -0.1778 -0.2794)
							(mid -0.249642 -0.249642)
							(end -0.2794 -0.1778)
						)
						(arc
							(start -0.2794 0.1778)
							(mid -0.249642 0.249642)
							(end -0.1778 0.2794)
						)
						(arc
							(start 0.1778 0.2794)
							(mid 0.249642 0.249642)
							(end 0.2794 0.1778)
						)
						(arc
							(start 0.2794 -0.1778)
							(mid 0.249642 -0.249642)
							(end 0.1778 -0.2794)
						)
					)
					(width 0)
					(fill yes)
				)
			)
		)
	)
	(footprint ""
		(layer "F.Cu")
		(at 216.069672 -54.854856 -90)
		(property "Reference" "R470"
			(at 0 0 270)
			(layer "F.SilkS")
			(hide yes)
			(effects
				(font
					(size 1.27 1.27)
				)
			)
		)
		(property "Value" "200KR2F-L-GP"
			(at 0.064008 -3.993896 270)
			(unlocked yes)
			(layer "F.Fab")
			(hide yes)
			(effects
				(font
					(size 1.016 1.016)
					(thickness 0.1524)
				)
			)
		)
		(property "Device Type" "R402H16"
			(at 0.064008 -5.517896 270)
			(unlocked yes)
			(layer "F.Fab")
			(hide yes)
			(effects
				(font
					(size 1.016 1.016)
					(thickness 0.1524)
				)
			)
		)
		(duplicate_pad_numbers_are_jumpers no)
		(fp_line
			(start -0.508 -0.9398)
			(end -0.508 0.9398)
			(stroke
				(width 0.1524)
				(type default)
			)
			(layer "F.SilkS")
		)
		(fp_line
			(start 0.508 -0.9398)
			(end -0.508 -0.9398)
			(stroke
				(width 0.1524)
				(type default)
			)
			(layer "F.SilkS")
		)
		(fp_rect
			(start -0.508 0.9398)
			(end 0.508 -0.9398)
			(stroke
				(width 0)
				(type default)
			)
			(fill no)
			(layer "F.CrtYd")
		)
		(fp_rect
			(start -0.508 0.9398)
			(end 0.508 -0.9398)
			(stroke
				(width 0)
				(type default)
			)
			(fill no)
			(layer "F.Fab")
		)
		(pad "1" smd custom
			(at 0 -0.4445 270)
			(size 0.1397 0.1397)
			(layers "F.Cu" "F.Mask" "F.Paste")
			(net "P5V_MODE")
			(options
				(clearance outline)
				(anchor circle)
			)
			(primitives
				(gr_poly
					(pts
						(arc
							(start -0.1778 -0.2794)
							(mid -0.249642 -0.249642)
							(end -0.2794 -0.1778)
						)
						(arc
							(start -0.2794 0.1778)
							(mid -0.249642 0.249642)
							(end -0.1778 0.2794)
						)
						(arc
							(start 0.1778 0.2794)
							(mid 0.249642 0.249642)
							(end 0.2794 0.1778)
						)
						(arc
							(start 0.2794 -0.1778)
							(mid 0.249642 -0.249642)
							(end 0.1778 -0.2794)
						)
					)
					(width 0)
					(fill yes)
				)
			)
		)
		(pad "2" smd custom
			(at 0 0.4445 270)
			(size 0.1397 0.1397)
			(layers "F.Cu" "F.Mask" "F.Paste")
			(net "PWRGD_P5V_STBY")
			(options
				(clearance outline)
				(anchor circle)
			)
			(primitives
				(gr_poly
					(pts
						(arc
							(start -0.1778 -0.2794)
							(mid -0.249642 -0.249642)
							(end -0.2794 -0.1778)
						)
						(arc
							(start -0.2794 0.1778)
							(mid -0.249642 0.249642)
							(end -0.1778 0.2794)
						)
						(arc
							(start 0.1778 0.2794)
							(mid 0.249642 0.249642)
							(end 0.2794 0.1778)
						)
						(arc
							(start 0.2794 -0.1778)
							(mid 0.249642 -0.249642)
							(end 0.1778 -0.2794)
						)
					)
					(width 0)
					(fill yes)
				)
			)
		)
	)
	(footprint ""
		(layer "F.Cu")
		(at 46.450504 -161.231072 180)
		(property "Reference" "R179"
			(at 0 0 180)
			(layer "F.SilkS")
			(hide yes)
			(effects
				(font
					(size 1.27 1.27)
				)
			)
		)
		(property "Value" "2K2R2F-GP"
			(at 0.064008 -3.993896 180)
			(unlocked yes)
			(layer "F.Fab")
			(hide yes)
			(effects
				(font
					(size 1.016 1.016)
					(thickness 0.1524)
				)
			)
		)
		(property "Device Type" "R402H16"
			(at 0.064008 -5.517896 180)
			(unlocked yes)
			(layer "F.Fab")
			(hide yes)
			(effects
				(font
					(size 1.016 1.016)
					(thickness 0.1524)
				)
			)
		)
		(duplicate_pad_numbers_are_jumpers no)
		(fp_line
			(start 0.508 -0.9398)
			(end -0.508 -0.9398)
			(stroke
				(width 0.1524)
				(type default)
			)
			(layer "F.SilkS")
		)
		(fp_line
			(start -0.508 -0.9398)
			(end -0.508 0.9398)
			(stroke
				(width 0.1524)
				(type default)
			)
			(layer "F.SilkS")
		)
		(fp_rect
			(start -0.508 0.9398)
			(end 0.508 -0.9398)
			(stroke
				(width 0)
				(type default)
			)
			(fill no)
			(layer "F.CrtYd")
		)
		(fp_rect
			(start -0.508 0.9398)
			(end 0.508 -0.9398)
			(stroke
				(width 0)
				(type default)
			)
			(fill no)
			(layer "F.Fab")
		)
		(pad "1" smd custom
			(at 0 -0.4445 180)
			(size 0.1397 0.1397)
			(layers "F.Cu" "F.Mask" "F.Paste")
			(net "I2C_DPB_SCL_OUT")
			(options
				(clearance outline)
				(anchor circle)
			)
			(primitives
				(gr_poly
					(pts
						(arc
							(start -0.1778 -0.2794)
							(mid -0.249642 -0.249642)
							(end -0.2794 -0.1778)
						)
						(arc
							(start -0.2794 0.1778)
							(mid -0.249642 0.249642)
							(end -0.1778 0.2794)
						)
						(arc
							(start 0.1778 0.2794)
							(mid 0.249642 0.249642)
							(end 0.2794 0.1778)
						)
						(arc
							(start 0.2794 -0.1778)
							(mid 0.249642 -0.249642)
							(end 0.1778 -0.2794)
						)
					)
					(width 0)
					(fill yes)
				)
			)
		)
		(pad "2" smd custom
			(at 0 0.4445 180)
			(size 0.1397 0.1397)
			(layers "F.Cu" "F.Mask" "F.Paste")
			(net "P3V3_STBY")
			(options
				(clearance outline)
				(anchor circle)
			)
			(primitives
				(gr_poly
					(pts
						(arc
							(start -0.1778 -0.2794)
							(mid -0.249642 -0.249642)
							(end -0.2794 -0.1778)
						)
						(arc
							(start -0.2794 0.1778)
							(mid -0.249642 0.249642)
							(end -0.1778 0.2794)
						)
						(arc
							(start 0.1778 0.2794)
							(mid 0.249642 0.249642)
							(end 0.2794 0.1778)
						)
						(arc
							(start 0.2794 -0.1778)
							(mid 0.249642 -0.249642)
							(end 0.1778 -0.2794)
						)
					)
					(width 0)
					(fill yes)
				)
			)
		)
	)
	(footprint ""
		(layer "F.Cu")
		(at 10.791698 -141.008862 90)
		(property "Reference" "R228"
			(at 0 0 90)
			(layer "F.SilkS")
			(hide yes)
			(effects
				(font
					(size 1.27 1.27)
				)
			)
		)
		(property "Value" "120R2F-GP"
			(at 0.064008 -3.993896 90)
			(unlocked yes)
			(layer "F.Fab")
			(hide yes)
			(effects
				(font
					(size 1.016 1.016)
					(thickness 0.1524)
				)
			)
		)
		(property "Device Type" "R402H16"
			(at 0.064008 -5.517896 90)
			(unlocked yes)
			(layer "F.Fab")
			(hide yes)
			(effects
				(font
					(size 1.016 1.016)
					(thickness 0.1524)
				)
			)
		)
		(duplicate_pad_numbers_are_jumpers no)
		(fp_line
			(start 0.508 -0.9398)
			(end -0.508 -0.9398)
			(stroke
				(width 0.1524)
				(type default)
			)
			(layer "F.SilkS")
		)
		(fp_line
			(start -0.508 -0.9398)
			(end -0.508 0.9398)
			(stroke
				(width 0.1524)
				(type default)
			)
			(layer "F.SilkS")
		)
		(fp_rect
			(start -0.508 0.9398)
			(end 0.508 -0.9398)
			(stroke
				(width 0)
				(type default)
			)
			(fill no)
			(layer "F.CrtYd")
		)
		(fp_rect
			(start -0.508 0.9398)
			(end 0.508 -0.9398)
			(stroke
				(width 0)
				(type default)
			)
			(fill no)
			(layer "F.Fab")
		)
		(pad "1" smd custom
			(at 0 -0.4445 90)
			(size 0.1397 0.1397)
			(layers "F.Cu" "F.Mask" "F.Paste")
			(net "MEMWEN")
			(options
				(clearance outline)
				(anchor circle)
			)
			(primitives
				(gr_poly
					(pts
						(arc
							(start -0.1778 -0.2794)
							(mid -0.249642 -0.249642)
							(end -0.2794 -0.1778)
						)
						(arc
							(start -0.2794 0.1778)
							(mid -0.249642 0.249642)
							(end -0.1778 0.2794)
						)
						(arc
							(start 0.1778 0.2794)
							(mid 0.249642 0.249642)
							(end 0.2794 0.1778)
						)
						(arc
							(start 0.2794 -0.1778)
							(mid 0.249642 -0.249642)
							(end 0.1778 -0.2794)
						)
					)
					(width 0)
					(fill yes)
				)
			)
		)
		(pad "2" smd custom
			(at 0 0.4445 90)
			(size 0.1397 0.1397)
			(layers "F.Cu" "F.Mask" "F.Paste")
			(net "P1V2_STBY")
			(options
				(clearance outline)
				(anchor circle)
			)
			(primitives
				(gr_poly
					(pts
						(arc
							(start -0.1778 -0.2794)
							(mid -0.249642 -0.249642)
							(end -0.2794 -0.1778)
						)
						(arc
							(start -0.2794 0.1778)
							(mid -0.249642 0.249642)
							(end -0.1778 0.2794)
						)
						(arc
							(start 0.1778 0.2794)
							(mid 0.249642 0.249642)
							(end 0.2794 0.1778)
						)
						(arc
							(start 0.2794 -0.1778)
							(mid 0.249642 -0.249642)
							(end 0.1778 -0.2794)
						)
					)
					(width 0)
					(fill yes)
				)
			)
		)
	)
)
